(kicad_pcb
	(version 20260206)
	(generator "pcbnew")
	(generator_version "10.0")
	(general
		(thickness 1.6)
		(legacy_teardrops no)
	)
	(paper "A4")
	(title_block
		(title "panther-plus-userver — 13130-1b_20150205.brd")
		(comment 1 "Honey Badger (Wiwynn) / footprints 1187-1194 of 1509")
	)
	(layers
		(0 "F.Cu" signal "TOP")
		(4 "In1.Cu" signal "L2")
		(6 "In2.Cu" signal "L3")
		(8 "In3.Cu" signal "L4")
		(10 "In4.Cu" signal "L5")
		(12 "In5.Cu" signal "L6")
		(14 "In6.Cu" signal "L7")
		(16 "In7.Cu" signal "L8")
		(18 "In8.Cu" signal "L9")
		(20 "In9.Cu" signal "L10")
		(22 "In10.Cu" signal "L11")
		(2 "B.Cu" signal "BOTTOM")
		(9 "F.Adhes" user "F.Adhesive")
		(11 "B.Adhes" user "B.Adhesive")
		(13 "F.Paste" user "Package Geometry/Pastemask Top")
		(15 "B.Paste" user "Package Geometry/Pastemask Bottom")
		(5 "F.SilkS" user "Ref Des/Silkscreen Top")
		(7 "B.SilkS" user "Ref Des/Silkscreen Bottom")
		(1 "F.Mask" user "Board Geometry/Soldermask Top")
		(3 "B.Mask" user "Board Geometry/Soldermask Bottom")
		(17 "Dwgs.User" user "User.Drawings")
		(19 "Cmts.User" user "User.Comments")
		(21 "Eco1.User" user "User.Eco1")
		(23 "Eco2.User" user "User.Eco2")
		(25 "Edge.Cuts" user "Board Geometry/Outline")
		(27 "Margin" user)
		(31 "F.CrtYd" user "Package Geometry/Place Bound Top")
		(29 "B.CrtYd" user "Package Geometry/Place Bound Bottom")
		(35 "F.Fab" user "Ref Des/Assembly Top")
		(33 "B.Fab" user "Ref Des/Assembly Bottom")
	)
	(footprint ""
		(layer "B.Cu")
		(at 68.58 -25.146 180)
		(property "Reference" "PG5"
			(at 0 0 0)
			(layer "B.SilkS")
			(hide yes)
			(effects
				(font
					(size 1.27 1.27)
				)
				(justify mirror)
			)
		)
		(property "Value" "COPPER-CLOSE-GP-U"
			(at -0.0762 -2.8702 180)
			(unlocked yes)
			(layer "B.Fab")
			(hide yes)
			(effects
				(font
					(size 1.016 1.016)
					(thickness 0.1524)
				)
				(justify mirror)
			)
		)
		(property "Device Type" "CON2C-U"
			(at -0.0762 -4.3942 180)
			(unlocked yes)
			(layer "B.Fab")
			(hide yes)
			(effects
				(font
					(size 1.016 1.016)
					(thickness 0.1524)
				)
				(justify mirror)
			)
		)
		(duplicate_pad_numbers_are_jumpers no)
		(fp_rect
			(start 0.9398 0.9652)
			(end -0.9398 -0.9652)
			(stroke
				(width 0)
				(type default)
			)
			(fill no)
			(layer "B.CrtYd")
		)
		(fp_rect
			(start 0.9398 0.9652)
			(end -0.9398 -0.9652)
			(stroke
				(width 0)
				(type default)
			)
			(fill no)
			(layer "B.Fab")
		)
		(pad "1" smd custom
			(at 0 -0.5334)
			(size 0.17145 0.17145)
			(layers "B.Cu" "B.Mask" "B.Paste")
			(net "AGND_P1V8_STBY")
			(options
				(clearance outline)
				(anchor circle)
			)
			(primitives
				(gr_poly
					(pts
						(xy -0.127 -0.3429) (xy -0.127 -0.1651) (xy -0.635 0.3429) (xy 0.635 0.3429) (xy 0.127 -0.1651)
						(xy 0.127 -0.3429)
					)
					(width 0)
					(fill yes)
				)
			)
		)
		(pad "2" smd custom
			(at 0 0.5334)
			(size 0.17145 0.17145)
			(layers "B.Cu" "B.Mask" "B.Paste")
			(net "GND")
			(options
				(clearance outline)
				(anchor circle)
			)
			(primitives
				(gr_poly
					(pts
						(xy -0.635 -0.3429) (xy -0.127 0.1651) (xy -0.127 0.3429) (xy 0.127 0.3429) (xy 0.127 0.1651)
						(xy 0.635 -0.3429)
					)
					(width 0)
					(fill yes)
				)
			)
		)
	)
	(footprint ""
		(layer "B.Cu")
		(at 168.021 -12.600178 180)
		(property "Reference" "C297"
			(at 0 0 0)
			(layer "B.SilkS")
			(hide yes)
			(effects
				(font
					(size 1.27 1.27)
				)
				(justify mirror)
			)
		)
		(property "Value" "SC1U10V2KX-1GP"
			(at -1.8923 -1.2065 180)
			(unlocked yes)
			(layer "B.Fab")
			(hide yes)
			(effects
				(font
					(size 1.016 1.016)
					(thickness 0.1524)
				)
				(justify mirror)
			)
		)
		(property "Device Type" "C402H22"
			(at -1.8923 -2.7305 180)
			(unlocked yes)
			(layer "B.Fab")
			(hide yes)
			(effects
				(font
					(size 1.016 1.016)
					(thickness 0.1524)
				)
				(justify mirror)
			)
		)
		(duplicate_pad_numbers_are_jumpers no)
		(fp_rect
			(start 0.381 0.7366)
			(end -0.381 -0.7366)
			(stroke
				(width 0)
				(type default)
			)
			(fill no)
			(layer "B.CrtYd")
		)
		(fp_rect
			(start 0.381 0.7366)
			(end -0.381 -0.7366)
			(stroke
				(width 0)
				(type default)
			)
			(fill no)
			(layer "B.Fab")
		)
		(pad "1" smd custom
			(at 0 -0.4572)
			(size 0.1143 0.1143)
			(layers "B.Cu" "B.Mask" "B.Paste")
			(net "PV_VDDR")
			(options
				(clearance outline)
				(anchor circle)
			)
			(primitives
				(gr_poly
					(pts
						(arc
							(start -0.254 0.1778)
							(mid -0.239121 0.213721)
							(end -0.2032 0.2286)
						)
						(arc
							(start 0.2032 0.2286)
							(mid 0.239121 0.213721)
							(end 0.254 0.1778)
						)
						(arc
							(start 0.254 -0.1778)
							(mid 0.239121 -0.213721)
							(end 0.2032 -0.2286)
						)
						(arc
							(start -0.2032 -0.2286)
							(mid -0.239121 -0.213721)
							(end -0.254 -0.1778)
						)
					)
					(width 0)
					(fill yes)
				)
			)
		)
		(pad "2" smd custom
			(at 0 0.4572)
			(size 0.1143 0.1143)
			(layers "B.Cu" "B.Mask" "B.Paste")
			(net "GND")
			(options
				(clearance outline)
				(anchor circle)
			)
			(primitives
				(gr_poly
					(pts
						(arc
							(start -0.254 0.1778)
							(mid -0.239121 0.213721)
							(end -0.2032 0.2286)
						)
						(arc
							(start 0.2032 0.2286)
							(mid 0.239121 0.213721)
							(end 0.254 0.1778)
						)
						(arc
							(start 0.254 -0.1778)
							(mid 0.239121 -0.213721)
							(end 0.2032 -0.2286)
						)
						(arc
							(start -0.2032 -0.2286)
							(mid -0.239121 -0.213721)
							(end -0.254 -0.1778)
						)
					)
					(width 0)
					(fill yes)
				)
			)
		)
	)
	(footprint ""
		(layer "B.Cu")
		(at 82.266028 -18.197322 180)
		(property "Reference" "PU16"
			(at 0 0 0)
			(layer "B.SilkS")
			(hide yes)
			(effects
				(font
					(size 1.27 1.27)
				)
				(justify mirror)
			)
		)
		(property "Value" "TPS74801RGW-GP"
			(at 4.7244 -6.223 180)
			(unlocked yes)
			(layer "B.Fab")
			(hide yes)
			(effects
				(font
					(size 1.016 1.016)
					(thickness 0.1524)
				)
				(justify mirror)
			)
		)
		(property "Device Type" "QFN20-1G3D15H40"
			(at 4.7244 -7.747 180)
			(unlocked yes)
			(layer "B.Fab")
			(hide yes)
			(effects
				(font
					(size 1.016 1.016)
					(thickness 0.1524)
				)
				(justify mirror)
			)
		)
		(duplicate_pad_numbers_are_jumpers no)
		(fp_poly
			(pts
				(xy -1.3208 -2.884932) (xy -1.941068 -3.5052) (xy -0.700786 -3.5052)
			)
			(stroke
				(width 0)
				(type default)
			)
			(fill yes)
			(layer "B.SilkS")
		)
		(fp_rect
			(start 2.8829 2.8829)
			(end -2.8829 -2.8829)
			(stroke
				(width 0)
				(type default)
			)
			(fill no)
			(layer "B.CrtYd")
		)
		(fp_rect
			(start 2.8829 2.8829)
			(end -2.8829 -2.8829)
			(stroke
				(width 0)
				(type default)
			)
			(fill no)
			(layer "B.Fab")
		)
		(pad "1" smd rect
			(at -1.299972 -2.347722)
			(size 0.3556 0.8128)
			(layers "B.Cu" "B.Mask" "B.Paste")
			(net "TPS74801_1V35_OUT")
		)
		(pad "2" smd rect
			(at -0.649986 -2.347722)
			(size 0.3556 0.8128)
			(layers "B.Cu" "B.Mask" "B.Paste")
			(net "GND")
		)
		(pad "3" smd rect
			(at 0 -2.347722)
			(size 0.3556 0.8128)
			(layers "B.Cu" "B.Mask" "B.Paste")
			(net "GND")
		)
		(pad "4" smd rect
			(at 0.649986 -2.347722)
			(size 0.3556 0.8128)
			(layers "B.Cu" "B.Mask" "B.Paste")
			(net "GND")
		)
		(pad "5" smd rect
			(at 1.299972 -2.347722)
			(size 0.3556 0.8128)
			(layers "B.Cu" "B.Mask" "B.Paste")
			(net "TPS74801_P1V35_IN")
		)
		(pad "6" smd rect
			(at 2.347722 -1.299972)
			(size 0.8128 0.3556)
			(layers "B.Cu" "B.Mask" "B.Paste")
			(net "TPS74801_P1V35_IN")
		)
		(pad "7" smd rect
			(at 2.347722 -0.649986)
			(size 0.8128 0.3556)
			(layers "B.Cu" "B.Mask" "B.Paste")
			(net "TPS74801_P1V35_IN")
		)
		(pad "8" smd rect
			(at 2.347722 0)
			(size 0.8128 0.3556)
			(layers "B.Cu" "B.Mask" "B.Paste")
			(net "TPS74801_P1V35_IN")
		)
		(pad "9" smd rect
			(at 2.347722 0.649986)
			(size 0.8128 0.3556)
			(layers "B.Cu" "B.Mask" "B.Paste")
			(net "PWRGD_P1V35_PG")
		)
		(pad "10" smd rect
			(at 2.347722 1.299972)
			(size 0.8128 0.3556)
			(layers "B.Cu" "B.Mask" "B.Paste")
			(net "TPS74801_1V35_BIAS")
		)
		(pad "11" smd rect
			(at 1.299972 2.347722)
			(size 0.3556 0.8128)
			(layers "B.Cu" "B.Mask" "B.Paste")
			(net "TPS74801_1V35_EN")
		)
		(pad "12" smd rect
			(at 0.649986 2.347722)
			(size 0.3556 0.8128)
			(layers "B.Cu" "B.Mask" "B.Paste")
			(net "GND")
		)
		(pad "13" smd rect
			(at 0 2.347722)
			(size 0.3556 0.8128)
			(layers "B.Cu" "B.Mask" "B.Paste")
			(net "GND")
		)
		(pad "14" smd rect
			(at -0.649986 2.347722)
			(size 0.3556 0.8128)
			(layers "B.Cu" "B.Mask" "B.Paste")
			(net "GND")
		)
		(pad "15" smd rect
			(at -1.299972 2.347722)
			(size 0.3556 0.8128)
			(layers "B.Cu" "B.Mask" "B.Paste")
			(net "TPS74801_1V35_SS")
		)
		(pad "16" smd rect
			(at -2.347722 1.299972)
			(size 0.8128 0.3556)
			(layers "B.Cu" "B.Mask" "B.Paste")
			(net "TPS74801_1V35_FB")
		)
		(pad "17" smd rect
			(at -2.347722 0.649986)
			(size 0.8128 0.3556)
			(layers "B.Cu" "B.Mask" "B.Paste")
			(net "GND")
		)
		(pad "18" smd rect
			(at -2.347722 0)
			(size 0.8128 0.3556)
			(layers "B.Cu" "B.Mask" "B.Paste")
			(net "TPS74801_1V35_OUT")
		)
		(pad "19" smd rect
			(at -2.347722 -0.649986)
			(size 0.8128 0.3556)
			(layers "B.Cu" "B.Mask" "B.Paste")
			(net "TPS74801_1V35_OUT")
		)
		(pad "20" smd rect
			(at -2.347722 -1.299972)
			(size 0.8128 0.3556)
			(layers "B.Cu" "B.Mask" "B.Paste")
			(net "TPS74801_1V35_OUT")
		)
		(pad "21" smd rect
			(at 0 0)
			(size 3.2512 3.2512)
			(layers "B.Cu" "B.Mask" "B.Paste")
			(net "GND")
		)
	)
	(footprint ""
		(layer "B.Cu")
		(at 112.395 -29.099002 90)
		(property "Reference" "C228"
			(at 0 0 90)
			(layer "B.SilkS")
			(hide yes)
			(effects
				(font
					(size 1.27 1.27)
				)
				(justify mirror)
			)
		)
		(property "Value" "SC1U10V2KX-1GP"
			(at -1.1811 -2.7051 90)
			(unlocked yes)
			(layer "B.Fab")
			(hide yes)
			(effects
				(font
					(size 1.016 1.016)
					(thickness 0.1524)
				)
				(justify mirror)
			)
		)
		(property "Device Type" "C402H22"
			(at -1.1811 -4.2291 90)
			(unlocked yes)
			(layer "B.Fab")
			(hide yes)
			(effects
				(font
					(size 1.016 1.016)
					(thickness 0.1524)
				)
				(justify mirror)
			)
		)
		(duplicate_pad_numbers_are_jumpers no)
		(fp_rect
			(start 0.381 0.7366)
			(end -0.381 -0.7366)
			(stroke
				(width 0)
				(type default)
			)
			(fill no)
			(layer "B.CrtYd")
		)
		(fp_rect
			(start 0.381 0.7366)
			(end -0.381 -0.7366)
			(stroke
				(width 0)
				(type default)
			)
			(fill no)
			(layer "B.Fab")
		)
		(pad "1" smd custom
			(at 0 -0.4572 270)
			(size 0.1143 0.1143)
			(layers "B.Cu" "B.Mask" "B.Paste")
			(net "PV_VDDR")
			(options
				(clearance outline)
				(anchor circle)
			)
			(primitives
				(gr_poly
					(pts
						(arc
							(start -0.254 0.1778)
							(mid -0.239121 0.213721)
							(end -0.2032 0.2286)
						)
						(arc
							(start 0.2032 0.2286)
							(mid 0.239121 0.213721)
							(end 0.254 0.1778)
						)
						(arc
							(start 0.254 -0.1778)
							(mid 0.239121 -0.213721)
							(end 0.2032 -0.2286)
						)
						(arc
							(start -0.2032 -0.2286)
							(mid -0.239121 -0.213721)
							(end -0.254 -0.1778)
						)
					)
					(width 0)
					(fill yes)
				)
			)
		)
		(pad "2" smd custom
			(at 0 0.4572 270)
			(size 0.1143 0.1143)
			(layers "B.Cu" "B.Mask" "B.Paste")
			(net "GND")
			(options
				(clearance outline)
				(anchor circle)
			)
			(primitives
				(gr_poly
					(pts
						(arc
							(start -0.254 0.1778)
							(mid -0.239121 0.213721)
							(end -0.2032 0.2286)
						)
						(arc
							(start 0.2032 0.2286)
							(mid 0.239121 0.213721)
							(end 0.254 0.1778)
						)
						(arc
							(start 0.254 -0.1778)
							(mid 0.239121 -0.213721)
							(end 0.2032 -0.2286)
						)
						(arc
							(start -0.2032 -0.2286)
							(mid -0.239121 -0.213721)
							(end -0.254 -0.1778)
						)
					)
					(width 0)
					(fill yes)
				)
			)
		)
	)
	(footprint ""
		(layer "B.Cu")
		(at 102.362 -67.31)
		(property "Reference" "PR6"
			(at 0 0 0)
			(layer "B.SilkS")
			(hide yes)
			(effects
				(font
					(size 1.27 1.27)
				)
				(justify mirror)
			)
		)
		(property "Value" "200KR2F-L-GP"
			(at -0.064008 -3.993896 0)
			(unlocked yes)
			(layer "B.Fab")
			(hide yes)
			(effects
				(font
					(size 1.016 1.016)
					(thickness 0.1524)
				)
				(justify mirror)
			)
		)
		(property "Device Type" "R402H16"
			(at -0.064008 -5.517896 0)
			(unlocked yes)
			(layer "B.Fab")
			(hide yes)
			(effects
				(font
					(size 1.016 1.016)
					(thickness 0.1524)
				)
				(justify mirror)
			)
		)
		(duplicate_pad_numbers_are_jumpers no)
		(fp_rect
			(start 0.381 0.8382)
			(end -0.381 -0.8382)
			(stroke
				(width 0)
				(type default)
			)
			(fill no)
			(layer "B.CrtYd")
		)
		(fp_rect
			(start 0.381 0.8382)
			(end -0.381 -0.8382)
			(stroke
				(width 0)
				(type default)
			)
			(fill no)
			(layer "B.Fab")
		)
		(pad "1" smd custom
			(at 0 -0.4318 180)
			(size 0.127 0.127)
			(layers "B.Cu" "B.Mask" "B.Paste")
			(net "VR_P1V1_VFBR")
			(options
				(clearance outline)
				(anchor circle)
			)
			(primitives
				(gr_poly
					(pts
						(arc
							(start -0.2032 0.2794)
							(mid -0.239121 0.264521)
							(end -0.254 0.2286)
						)
						(arc
							(start -0.254 -0.2286)
							(mid -0.239121 -0.264521)
							(end -0.2032 -0.2794)
						)
						(arc
							(start 0.2032 -0.2794)
							(mid 0.239121 -0.264521)
							(end 0.254 -0.2286)
						)
						(arc
							(start 0.254 0.2286)
							(mid 0.239121 0.264521)
							(end 0.2032 0.2794)
						)
					)
					(width 0)
					(fill yes)
				)
			)
		)
		(pad "2" smd custom
			(at 0 0.4318 180)
			(size 0.127 0.127)
			(layers "B.Cu" "B.Mask" "B.Paste")
			(net "VR_P1V1_VFB")
			(options
				(clearance outline)
				(anchor circle)
			)
			(primitives
				(gr_poly
					(pts
						(arc
							(start -0.2032 0.2794)
							(mid -0.239121 0.264521)
							(end -0.254 0.2286)
						)
						(arc
							(start -0.254 -0.2286)
							(mid -0.239121 -0.264521)
							(end -0.2032 -0.2794)
						)
						(arc
							(start 0.2032 -0.2794)
							(mid 0.239121 -0.264521)
							(end 0.254 -0.2286)
						)
						(arc
							(start 0.254 0.2286)
							(mid 0.239121 0.264521)
							(end 0.2032 0.2794)
						)
					)
					(width 0)
					(fill yes)
				)
			)
		)
	)
	(footprint ""
		(layer "B.Cu")
		(at 92.71 -30.099 90)
		(property "Reference" "C225"
			(at 0 0 90)
			(layer "B.SilkS")
			(hide yes)
			(effects
				(font
					(size 1.27 1.27)
				)
				(justify mirror)
			)
		)
		(property "Value" "SC1U10V2KX-1GP"
			(at -1.1811 -2.7051 90)
			(unlocked yes)
			(layer "B.Fab")
			(hide yes)
			(effects
				(font
					(size 1.016 1.016)
					(thickness 0.1524)
				)
				(justify mirror)
			)
		)
		(property "Device Type" "C402H22"
			(at -1.1811 -4.2291 90)
			(unlocked yes)
			(layer "B.Fab")
			(hide yes)
			(effects
				(font
					(size 1.016 1.016)
					(thickness 0.1524)
				)
				(justify mirror)
			)
		)
		(duplicate_pad_numbers_are_jumpers no)
		(fp_rect
			(start 0.381 0.7366)
			(end -0.381 -0.7366)
			(stroke
				(width 0)
				(type default)
			)
			(fill no)
			(layer "B.CrtYd")
		)
		(fp_rect
			(start 0.381 0.7366)
			(end -0.381 -0.7366)
			(stroke
				(width 0)
				(type default)
			)
			(fill no)
			(layer "B.Fab")
		)
		(pad "1" smd custom
			(at 0 -0.4572 270)
			(size 0.1143 0.1143)
			(layers "B.Cu" "B.Mask" "B.Paste")
			(net "P1V0")
			(options
				(clearance outline)
				(anchor circle)
			)
			(primitives
				(gr_poly
					(pts
						(arc
							(start -0.254 0.1778)
							(mid -0.239121 0.213721)
							(end -0.2032 0.2286)
						)
						(arc
							(start 0.2032 0.2286)
							(mid 0.239121 0.213721)
							(end 0.254 0.1778)
						)
						(arc
							(start 0.254 -0.1778)
							(mid 0.239121 -0.213721)
							(end 0.2032 -0.2286)
						)
						(arc
							(start -0.2032 -0.2286)
							(mid -0.239121 -0.213721)
							(end -0.254 -0.1778)
						)
					)
					(width 0)
					(fill yes)
				)
			)
		)
		(pad "2" smd custom
			(at 0 0.4572 270)
			(size 0.1143 0.1143)
			(layers "B.Cu" "B.Mask" "B.Paste")
			(net "GND")
			(options
				(clearance outline)
				(anchor circle)
			)
			(primitives
				(gr_poly
					(pts
						(arc
							(start -0.254 0.1778)
							(mid -0.239121 0.213721)
							(end -0.2032 0.2286)
						)
						(arc
							(start 0.2032 0.2286)
							(mid 0.239121 0.213721)
							(end 0.254 0.1778)
						)
						(arc
							(start 0.254 -0.1778)
							(mid 0.239121 -0.213721)
							(end 0.2032 -0.2286)
						)
						(arc
							(start -0.2032 -0.2286)
							(mid -0.239121 -0.213721)
							(end -0.254 -0.1778)
						)
					)
					(width 0)
					(fill yes)
				)
			)
		)
	)
	(footprint ""
		(layer "B.Cu")
		(at 94.869 -27.702002 180)
		(property "Reference" "TP52"
			(at 0 0 0)
			(layer "B.SilkS")
			(hide yes)
			(effects
				(font
					(size 1.27 1.27)
				)
				(justify mirror)
			)
		)
		(property "Value" "TPAD24"
			(at 0 -2.9972 180)
			(unlocked yes)
			(layer "B.Fab")
			(hide yes)
			(effects
				(font
					(size 1.016 1.016)
					(thickness 0.1524)
				)
				(justify mirror)
			)
		)
		(property "Device Type" "TPAD24"
			(at 0 -4.5212 180)
			(unlocked yes)
			(layer "B.Fab")
			(hide yes)
			(effects
				(font
					(size 1.016 1.016)
					(thickness 0.1524)
				)
				(justify mirror)
			)
		)
		(duplicate_pad_numbers_are_jumpers no)
		(fp_poly
			(pts
				(arc
					(start -0.3048 0)
					(mid 0.3048 0)
					(end -0.3048 0)
				)
			)
			(stroke
				(width 0)
				(type default)
			)
			(fill no)
			(layer "B.CrtYd")
		)
		(fp_poly
			(pts
				(arc
					(start -0.6096 0)
					(mid 0.6096 0)
					(end -0.6096 0)
				)
			)
			(stroke
				(width 0)
				(type default)
			)
			(fill no)
			(layer "B.Fab")
		)
		(pad "1" smd circle
			(at 0 0)
			(size 0.6096 0.6096)
			(layers "B.Cu" "B.Mask" "B.Paste")
			(net "TP_CPU_RSVD16")
		)
	)
	(footprint ""
		(layer "B.Cu")
		(at 133.223 -23.622 -90)
		(property "Reference" "R48"
			(at 0 0 90)
			(layer "B.SilkS")
			(hide yes)
			(effects
				(font
					(size 1.27 1.27)
				)
				(justify mirror)
			)
		)
		(property "Value" "0R2J-2-GP"
			(at -0.064008 -3.993896 270)
			(unlocked yes)
			(layer "B.Fab")
			(hide yes)
			(effects
				(font
					(size 1.016 1.016)
					(thickness 0.1524)
				)
				(justify mirror)
			)
		)
		(property "Device Type" "R402H16"
			(at -0.064008 -5.517896 270)
			(unlocked yes)
			(layer "B.Fab")
			(hide yes)
			(effects
				(font
					(size 1.016 1.016)
					(thickness 0.1524)
				)
				(justify mirror)
			)
		)
		(duplicate_pad_numbers_are_jumpers no)
		(fp_rect
			(start 0.381 0.8382)
			(end -0.381 -0.8382)
			(stroke
				(width 0)
				(type default)
			)
			(fill no)
			(layer "B.CrtYd")
		)
		(fp_rect
			(start 0.381 0.8382)
			(end -0.381 -0.8382)
			(stroke
				(width 0)
				(type default)
			)
			(fill no)
			(layer "B.Fab")
		)
		(pad "1" smd custom
			(at 0 -0.4318 90)
			(size 0.127 0.127)
			(layers "B.Cu" "B.Mask" "B.Paste")
			(net "BIOS_POST_COMPLETE_R")
			(options
				(clearance outline)
				(anchor circle)
			)
			(primitives
				(gr_poly
					(pts
						(arc
							(start -0.2032 0.2794)
							(mid -0.239121 0.264521)
							(end -0.254 0.2286)
						)
						(arc
							(start -0.254 -0.2286)
							(mid -0.239121 -0.264521)
							(end -0.2032 -0.2794)
						)
						(arc
							(start 0.2032 -0.2794)
							(mid 0.239121 -0.264521)
							(end 0.254 -0.2286)
						)
						(arc
							(start 0.254 0.2286)
							(mid 0.239121 0.264521)
							(end 0.2032 0.2794)
						)
					)
					(width 0)
					(fill yes)
				)
			)
		)
		(pad "2" smd custom
			(at 0 0.4318 90)
			(size 0.127 0.127)
			(layers "B.Cu" "B.Mask" "B.Paste")
			(net "BIOS_POST_CMPLT#")
			(options
				(clearance outline)
				(anchor circle)
			)
			(primitives
				(gr_poly
					(pts
						(arc
							(start -0.2032 0.2794)
							(mid -0.239121 0.264521)
							(end -0.254 0.2286)
						)
						(arc
							(start -0.254 -0.2286)
							(mid -0.239121 -0.264521)
							(end -0.2032 -0.2794)
						)
						(arc
							(start 0.2032 -0.2794)
							(mid 0.239121 -0.264521)
							(end 0.254 -0.2286)
						)
						(arc
							(start 0.254 0.2286)
							(mid 0.239121 0.264521)
							(end 0.2032 0.2794)
						)
					)
					(width 0)
					(fill yes)
				)
			)
		)
	)
)
